(kicad_pcb
	(version 20260206)
	(generator "pcbnew")
	(generator_version "10.0")
	(general
		(thickness 1.6)
		(legacy_teardrops no)
	)
	(paper "A4")
	(title_block
		(title "Bryce Canyon_F.DPB_16315-1-OCP.brd")
		(comment 1 "Bryce Canyon / footprints 1806-1811 of 2223")
	)
	(layers
		(0 "F.Cu" signal "TOP")
		(4 "In1.Cu" signal "L2GND")
		(6 "In2.Cu" signal "L3")
		(8 "In3.Cu" signal "L4GND")
		(10 "In4.Cu" signal "L5")
		(12 "In5.Cu" signal "L6VCC")
		(14 "In6.Cu" signal "L7VCC")
		(16 "In7.Cu" signal "L8")
		(18 "In8.Cu" signal "L9GND")
		(20 "In9.Cu" signal "L10")
		(22 "In10.Cu" signal "L11GND")
		(2 "B.Cu" signal "BOTTOM")
		(9 "F.Adhes" user "F.Adhesive")
		(11 "B.Adhes" user "B.Adhesive")
		(13 "F.Paste" user "Package Geometry/Pastemask Top")
		(15 "B.Paste" user "Package Geometry/Pastemask Bottom")
		(5 "F.SilkS" user "Ref Des/Silkscreen Top")
		(7 "B.SilkS" user "Ref Des/Silkscreen Bottom")
		(1 "F.Mask" user "Board Geometry/Soldermask Top")
		(3 "B.Mask" user "Board Geometry/Soldermask Bottom")
		(17 "Dwgs.User" user "User.Drawings")
		(19 "Cmts.User" user "User.Comments")
		(21 "Eco1.User" user "User.Eco1")
		(23 "Eco2.User" user "User.Eco2")
		(25 "Edge.Cuts" user "Board Geometry/Outline")
		(27 "Margin" user)
		(31 "F.CrtYd" user "Package Geometry/Place Bound Top")
		(29 "B.CrtYd" user "Package Geometry/Place Bound Bottom")
		(35 "F.Fab" user "Ref Des/Assembly Top")
		(33 "B.Fab" user "Ref Des/Assembly Bottom")
	)
	(footprint ""
		(layer "F.Cu")
		(at 43.208194 -130.269996 -90)
		(property "Reference" "R504"
			(at 0 0 270)
			(layer "F.SilkS")
			(hide yes)
			(effects
				(font
					(size 1.27 1.27)
				)
			)
		)
		(property "Value" "4K7R2J-2-GP"
			(at 0.064008 -3.993896 270)
			(unlocked yes)
			(layer "F.Fab")
			(hide yes)
			(effects
				(font
					(size 1.016 1.016)
					(thickness 0.1524)
				)
			)
		)
		(property "Device Type" "R402H16"
			(at 0.064008 -5.517896 270)
			(unlocked yes)
			(layer "F.Fab")
			(hide yes)
			(effects
				(font
					(size 1.016 1.016)
					(thickness 0.1524)
				)
			)
		)
		(duplicate_pad_numbers_are_jumpers no)
		(fp_line
			(start -0.508 -0.9398)
			(end -0.508 0.9398)
			(stroke
				(width 0.1524)
				(type default)
			)
			(layer "F.SilkS")
		)
		(fp_line
			(start 0.508 -0.9398)
			(end -0.508 -0.9398)
			(stroke
				(width 0.1524)
				(type default)
			)
			(layer "F.SilkS")
		)
		(fp_rect
			(start -0.508 0.9398)
			(end 0.508 -0.9398)
			(stroke
				(width 0)
				(type default)
			)
			(fill no)
			(layer "F.CrtYd")
		)
		(fp_rect
			(start -0.508 0.9398)
			(end 0.508 -0.9398)
			(stroke
				(width 0)
				(type default)
			)
			(fill no)
			(layer "F.Fab")
		)
		(pad "1" smd custom
			(at 0 -0.4445 270)
			(size 0.1397 0.1397)
			(layers "F.Cu" "F.Mask" "F.Paste")
			(net "DRIVE_A_13_ACT")
			(options
				(clearance outline)
				(anchor circle)
			)
			(primitives
				(gr_poly
					(pts
						(arc
							(start -0.1778 -0.2794)
							(mid -0.249642 -0.249642)
							(end -0.2794 -0.1778)
						)
						(arc
							(start -0.2794 0.1778)
							(mid -0.249642 0.249642)
							(end -0.1778 0.2794)
						)
						(arc
							(start 0.1778 0.2794)
							(mid 0.249642 0.249642)
							(end 0.2794 0.1778)
						)
						(arc
							(start 0.2794 -0.1778)
							(mid 0.249642 -0.249642)
							(end 0.1778 -0.2794)
						)
					)
					(width 0)
					(fill yes)
				)
			)
		)
		(pad "2" smd custom
			(at 0 0.4445 270)
			(size 0.1397 0.1397)
			(layers "F.Cu" "F.Mask" "F.Paste")
			(net "GND")
			(options
				(clearance outline)
				(anchor circle)
			)
			(primitives
				(gr_poly
					(pts
						(arc
							(start -0.1778 -0.2794)
							(mid -0.249642 -0.249642)
							(end -0.2794 -0.1778)
						)
						(arc
							(start -0.2794 0.1778)
							(mid -0.249642 0.249642)
							(end -0.1778 0.2794)
						)
						(arc
							(start 0.1778 0.2794)
							(mid 0.249642 0.249642)
							(end 0.2794 0.1778)
						)
						(arc
							(start 0.2794 -0.1778)
							(mid 0.249642 -0.249642)
							(end 0.1778 -0.2794)
						)
					)
					(width 0)
					(fill yes)
				)
			)
		)
	)
	(footprint ""
		(layer "F.Cu")
		(at 471.301318 -41.52265)
		(property "Reference" "R947"
			(at 0 0 0)
			(layer "F.SilkS")
			(hide yes)
			(effects
				(font
					(size 1.27 1.27)
				)
			)
		)
		(property "Value" "4K7R2J-2-GP"
			(at 0.064008 -3.993896 0)
			(unlocked yes)
			(layer "F.Fab")
			(hide yes)
			(effects
				(font
					(size 1.016 1.016)
					(thickness 0.1524)
				)
			)
		)
		(property "Device Type" "R402H16"
			(at 0.064008 -5.517896 0)
			(unlocked yes)
			(layer "F.Fab")
			(hide yes)
			(effects
				(font
					(size 1.016 1.016)
					(thickness 0.1524)
				)
			)
		)
		(duplicate_pad_numbers_are_jumpers no)
		(fp_line
			(start -0.508 -0.9398)
			(end -0.508 0.9398)
			(stroke
				(width 0.1524)
				(type default)
			)
			(layer "F.SilkS")
		)
		(fp_line
			(start 0.508 -0.9398)
			(end -0.508 -0.9398)
			(stroke
				(width 0.1524)
				(type default)
			)
			(layer "F.SilkS")
		)
		(fp_rect
			(start -0.508 0.9398)
			(end 0.508 -0.9398)
			(stroke
				(width 0)
				(type default)
			)
			(fill no)
			(layer "F.CrtYd")
		)
		(fp_rect
			(start -0.508 0.9398)
			(end 0.508 -0.9398)
			(stroke
				(width 0)
				(type default)
			)
			(fill no)
			(layer "F.Fab")
		)
		(pad "1" smd custom
			(at 0 -0.4445)
			(size 0.1397 0.1397)
			(layers "F.Cu" "F.Mask" "F.Paste")
			(net "SW_PWR_R_HDD35")
			(options
				(clearance outline)
				(anchor circle)
			)
			(primitives
				(gr_poly
					(pts
						(arc
							(start -0.1778 -0.2794)
							(mid -0.249642 -0.249642)
							(end -0.2794 -0.1778)
						)
						(arc
							(start -0.2794 0.1778)
							(mid -0.249642 0.249642)
							(end -0.1778 0.2794)
						)
						(arc
							(start 0.1778 0.2794)
							(mid 0.249642 0.249642)
							(end 0.2794 0.1778)
						)
						(arc
							(start 0.2794 -0.1778)
							(mid 0.249642 -0.249642)
							(end 0.1778 -0.2794)
						)
					)
					(width 0)
					(fill yes)
				)
			)
		)
		(pad "2" smd custom
			(at 0 0.4445)
			(size 0.1397 0.1397)
			(layers "F.Cu" "F.Mask" "F.Paste")
			(net "GND")
			(options
				(clearance outline)
				(anchor circle)
			)
			(primitives
				(gr_poly
					(pts
						(arc
							(start -0.1778 -0.2794)
							(mid -0.249642 -0.249642)
							(end -0.2794 -0.1778)
						)
						(arc
							(start -0.2794 0.1778)
							(mid -0.249642 0.249642)
							(end -0.1778 0.2794)
						)
						(arc
							(start 0.1778 0.2794)
							(mid 0.249642 0.249642)
							(end 0.2794 0.1778)
						)
						(arc
							(start 0.2794 -0.1778)
							(mid 0.249642 -0.249642)
							(end 0.1778 -0.2794)
						)
					)
					(width 0)
					(fill yes)
				)
			)
		)
	)
	(footprint ""
		(layer "F.Cu")
		(at 30.935676 -245.38305 -90)
		(property "Reference" "R1214"
			(at 0 0 270)
			(layer "F.SilkS")
			(hide yes)
			(effects
				(font
					(size 1.27 1.27)
				)
			)
		)
		(property "Value" "3D01R5F-GP"
			(at 0 -8.9535 270)
			(unlocked yes)
			(layer "F.Fab")
			(hide yes)
			(effects
				(font
					(size 1.27 1.016)
					(thickness 0.1524)
				)
			)
		)
		(property "Device Type" "R805H24"
			(at 0 -10.6299 270)
			(unlocked yes)
			(layer "F.Fab")
			(hide yes)
			(effects
				(font
					(size 1.27 1.016)
					(thickness 0.1524)
				)
			)
		)
		(duplicate_pad_numbers_are_jumpers no)
		(fp_line
			(start -0.889 1.7018)
			(end 0.889 1.7018)
			(stroke
				(width 0.1524)
				(type default)
			)
			(layer "F.SilkS")
		)
		(fp_line
			(start 0.889 1.7018)
			(end 0.889 -0.508)
			(stroke
				(width 0.1524)
				(type default)
			)
			(layer "F.SilkS")
		)
		(fp_line
			(start -0.889 0.0762)
			(end -0.889 1.7018)
			(stroke
				(width 0.1524)
				(type default)
			)
			(layer "F.SilkS")
		)
		(fp_line
			(start -0.889 -1.7018)
			(end -0.889 0.2794)
			(stroke
				(width 0.1524)
				(type default)
			)
			(layer "F.SilkS")
		)
		(fp_line
			(start 0.889 -1.7018)
			(end 0.889 -0.381)
			(stroke
				(width 0.1524)
				(type default)
			)
			(layer "F.SilkS")
		)
		(fp_line
			(start 0.889 -1.7018)
			(end -0.889 -1.7018)
			(stroke
				(width 0.1524)
				(type default)
			)
			(layer "F.SilkS")
		)
		(fp_poly
			(pts
				(xy 0.9652 -1.778) (xy 0.9652 1.778) (xy -0.9652 1.778) (xy -0.9652 -1.778)
			)
			(stroke
				(width 0)
				(type default)
			)
			(fill no)
			(layer "F.CrtYd")
		)
		(fp_rect
			(start -0.9652 1.778)
			(end 0.9652 -1.778)
			(stroke
				(width 0)
				(type default)
			)
			(fill no)
			(layer "F.Fab")
		)
		(pad "1" smd rect
			(at 0 -0.9652 270)
			(size 1.397 1.143)
			(layers "F.Cu" "F.Mask" "F.Paste")
			(net "P5V_SNB")
		)
		(pad "2" smd rect
			(at 0 0.9652 270)
			(size 1.397 1.143)
			(layers "F.Cu" "F.Mask" "F.Paste")
			(net "GND")
		)
	)
	(footprint ""
		(layer "F.Cu")
		(at 339.37194 -127.767588 180)
		(property "Reference" "Q282"
			(at 0 0 180)
			(layer "F.SilkS")
			(hide yes)
			(effects
				(font
					(size 1.27 1.27)
				)
			)
		)
		(property "Value" "SSM3K324R-GP"
			(at 0.127 -8.9662 180)
			(unlocked yes)
			(layer "F.Fab")
			(hide yes)
			(effects
				(font
					(size 1.016 1.016)
					(thickness 0.1524)
				)
			)
		)
		(property "Device Type" "SOT23DGS2D4H35"
			(at 0.127 -10.4902 180)
			(unlocked yes)
			(layer "F.Fab")
			(hide yes)
			(effects
				(font
					(size 1.016 1.016)
					(thickness 0.1524)
				)
			)
		)
		(duplicate_pad_numbers_are_jumpers no)
		(fp_line
			(start 1.651 1.778)
			(end 1.651 -1.778)
			(stroke
				(width 0.1524)
				(type default)
			)
			(layer "F.SilkS")
		)
		(fp_line
			(start 1.651 -1.778)
			(end -1.651 -1.778)
			(stroke
				(width 0.1524)
				(type default)
			)
			(layer "F.SilkS")
		)
		(fp_line
			(start -1.651 1.778)
			(end 1.651 1.778)
			(stroke
				(width 0.1524)
				(type default)
			)
			(layer "F.SilkS")
		)
		(fp_line
			(start -1.651 -1.778)
			(end -1.651 1.778)
			(stroke
				(width 0.1524)
				(type default)
			)
			(layer "F.SilkS")
		)
		(fp_poly
			(pts
				(xy -1.778 1.8796) (xy -1.778 -1.8796) (xy 1.778 -1.8796) (xy 1.778 1.8796)
			)
			(stroke
				(width 0)
				(type default)
			)
			(fill no)
			(layer "F.CrtYd")
		)
		(fp_poly
			(pts
				(xy -1.778 1.8796) (xy -1.778 -1.8796) (xy 1.778 -1.8796) (xy 1.778 1.8796)
			)
			(stroke
				(width 0)
				(type default)
			)
			(fill no)
			(layer "F.Fab")
		)
		(pad "D" smd custom
			(at 0 -0.9525 180)
			(size 0.1905 0.1905)
			(layers "F.Cu" "F.Mask" "F.Paste")
			(net "DRV_ACT_19_N")
			(options
				(clearance outline)
				(anchor circle)
			)
			(primitives
				(gr_poly
					(pts
						(arc
							(start -0.1778 0.5715)
							(mid -0.321484 0.511984)
							(end -0.381 0.3683)
						)
						(arc
							(start -0.381 -0.3683)
							(mid -0.321484 -0.511984)
							(end -0.1778 -0.5715)
						)
						(arc
							(start 0.1778 -0.5715)
							(mid 0.321484 -0.511984)
							(end 0.381 -0.3683)
						)
						(arc
							(start 0.381 0.3683)
							(mid 0.321484 0.511984)
							(end 0.1778 0.5715)
						)
					)
					(width 0)
					(fill yes)
				)
			)
		)
		(pad "G" smd custom
			(at -0.98425 0.9525 180)
			(size 0.1905 0.1905)
			(layers "F.Cu" "F.Mask" "F.Paste")
			(net "DRIVE_A_19_ACT")
			(options
				(clearance outline)
				(anchor circle)
			)
			(primitives
				(gr_poly
					(pts
						(arc
							(start -0.1778 0.5715)
							(mid -0.321484 0.511984)
							(end -0.381 0.3683)
						)
						(arc
							(start -0.381 -0.3683)
							(mid -0.321484 -0.511984)
							(end -0.1778 -0.5715)
						)
						(arc
							(start 0.1778 -0.5715)
							(mid 0.321484 -0.511984)
							(end 0.381 -0.3683)
						)
						(arc
							(start 0.381 0.3683)
							(mid 0.321484 0.511984)
							(end 0.1778 0.5715)
						)
					)
					(width 0)
					(fill yes)
				)
			)
		)
		(pad "S" smd custom
			(at 0.98425 0.9525 180)
			(size 0.1905 0.1905)
			(layers "F.Cu" "F.Mask" "F.Paste")
			(net "GND")
			(options
				(clearance outline)
				(anchor circle)
			)
			(primitives
				(gr_poly
					(pts
						(arc
							(start -0.1778 0.5715)
							(mid -0.321484 0.511984)
							(end -0.381 0.3683)
						)
						(arc
							(start -0.381 -0.3683)
							(mid -0.321484 -0.511984)
							(end -0.1778 -0.5715)
						)
						(arc
							(start 0.1778 -0.5715)
							(mid 0.321484 -0.511984)
							(end 0.381 -0.3683)
						)
						(arc
							(start 0.381 0.3683)
							(mid 0.321484 0.511984)
							(end 0.1778 0.5715)
						)
					)
					(width 0)
					(fill yes)
				)
			)
		)
	)
	(footprint ""
		(layer "F.Cu")
		(at 83.784948 -170.285918 180)
		(property "Reference" "Q83"
			(at 0 0 180)
			(layer "F.SilkS")
			(hide yes)
			(effects
				(font
					(size 1.27 1.27)
				)
			)
		)
		(property "Value" "AO4406AL-GP"
			(at -3.707384 -1.5367 180)
			(unlocked yes)
			(layer "F.Fab")
			(hide yes)
			(effects
				(font
					(size 1.016 1.016)
					(thickness 0.1524)
				)
			)
		)
		(property "Device Type" "SOIC8H69"
			(at -3.707384 -3.0607 180)
			(unlocked yes)
			(layer "F.Fab")
			(hide yes)
			(effects
				(font
					(size 1.016 1.016)
					(thickness 0.1524)
				)
			)
		)
		(duplicate_pad_numbers_are_jumpers no)
		(fp_line
			(start 2.1336 1.4224)
			(end 2.1336 -1.4224)
			(stroke
				(width 0.1524)
				(type default)
			)
			(layer "F.SilkS")
		)
		(fp_line
			(start 2.1336 -1.4224)
			(end -2.7432 -1.4224)
			(stroke
				(width 0.1524)
				(type default)
			)
			(layer "F.SilkS")
		)
		(fp_line
			(start -2.1844 -0.0508)
			(end -2.7178 0.508)
			(stroke
				(width 0.1524)
				(type default)
			)
			(layer "F.SilkS")
		)
		(fp_line
			(start -2.6289 3.4417)
			(end -2.6289 1.4732)
			(stroke
				(width 0.381)
				(type default)
			)
			(layer "F.SilkS")
		)
		(fp_line
			(start -2.7178 -0.508)
			(end -2.1844 -0.0508)
			(stroke
				(width 0.1524)
				(type default)
			)
			(layer "F.SilkS")
		)
		(fp_line
			(start -2.7432 1.4224)
			(end 2.1336 1.4224)
			(stroke
				(width 0.1524)
				(type default)
			)
			(layer "F.SilkS")
		)
		(fp_line
			(start -2.7432 1.4224)
			(end -2.6416 1.4224)
			(stroke
				(width 0.1524)
				(type default)
			)
			(layer "F.SilkS")
		)
		(fp_line
			(start -2.7432 -1.4224)
			(end -2.7432 1.4224)
			(stroke
				(width 0.1524)
				(type default)
			)
			(layer "F.SilkS")
		)
		(fp_poly
			(pts
				(xy -2.2098 -1.4224) (xy -2.2098 1.4224) (xy 2.2098 1.4224) (xy 2.2098 -1.4224)
			)
			(stroke
				(width 0)
				(type default)
			)
			(fill yes)
			(layer "F.SilkS")
		)
		(fp_rect
			(start -2.450084 2.999994)
			(end 2.450084 -2.999994)
			(stroke
				(width 0)
				(type default)
			)
			(fill no)
			(layer "F.CrtYd")
		)
		(fp_poly
			(pts
				(xy -2.8194 3.6322) (xy -2.8194 -3.6322) (xy 2.8194 -3.6322) (xy 2.8194 1.18364) (xy 2.450084 1.18364)
				(xy 2.450084 -2.999994) (xy -2.450084 -2.999994) (xy -2.450084 2.999994) (xy 2.450084 2.999994)
				(xy 2.450084 1.18618) (xy 2.8194 1.18618) (xy 2.8194 3.6322)
			)
			(stroke
				(width 0)
				(type default)
			)
			(fill no)
			(layer "F.CrtYd")
		)
		(fp_rect
			(start -2.8194 3.6322)
			(end 2.8194 -3.6322)
			(stroke
				(width 0)
				(type default)
			)
			(fill no)
			(layer "F.Fab")
		)
		(pad "1" smd rect
			(at -1.905 2.54 180)
			(size 0.635 1.651)
			(layers "F.Cu" "F.Mask" "F.Paste")
			(net "P5V_HDD14")
		)
		(pad "2" smd rect
			(at -0.635 2.54 180)
			(size 0.635 1.651)
			(layers "F.Cu" "F.Mask" "F.Paste")
			(net "P5V_HDD14")
		)
		(pad "3" smd rect
			(at 0.635 2.54 180)
			(size 0.635 1.651)
			(layers "F.Cu" "F.Mask" "F.Paste")
			(net "P5V_HDD14")
		)
		(pad "4" smd rect
			(at 1.905 2.54 180)
			(size 0.635 1.651)
			(layers "F.Cu" "F.Mask" "F.Paste")
			(net "SW_HDD_P14")
		)
		(pad "5" smd rect
			(at 1.905 -2.54 180)
			(size 0.635 1.651)
			(layers "F.Cu" "F.Mask" "F.Paste")
			(net "P5V_A_1")
		)
		(pad "6" smd rect
			(at 0.635 -2.54 180)
			(size 0.635 1.651)
			(layers "F.Cu" "F.Mask" "F.Paste")
			(net "P5V_A_1")
		)
		(pad "7" smd rect
			(at -0.635 -2.54 180)
			(size 0.635 1.651)
			(layers "F.Cu" "F.Mask" "F.Paste")
			(net "P5V_A_1")
		)
		(pad "8" smd rect
			(at -1.905 -2.54 180)
			(size 0.635 1.651)
			(layers "F.Cu" "F.Mask" "F.Paste")
			(net "P5V_A_1")
		)
	)
	(footprint ""
		(layer "F.Cu")
		(at 479.384614 -273.660616 -90)
		(property "Reference" "C182"
			(at 0 0 270)
			(layer "F.SilkS")
			(hide yes)
			(effects
				(font
					(size 1.27 1.27)
				)
			)
		)
		(property "Value" "SCD01U16V1KX-GP"
			(at -2.8321 -1.7399 270)
			(unlocked yes)
			(layer "F.Fab")
			(hide yes)
			(effects
				(font
					(size 1.016 1.016)
					(thickness 0.1524)
				)
			)
		)
		(property "Device Type" "C0201H13"
			(at -2.8321 -3.2639 270)
			(unlocked yes)
			(layer "F.Fab")
			(hide yes)
			(effects
				(font
					(size 1.016 1.016)
					(thickness 0.1524)
				)
			)
		)
		(duplicate_pad_numbers_are_jumpers no)
		(fp_rect
			(start -0.2794 0.6477)
			(end 0.2794 -0.6477)
			(stroke
				(width 0)
				(type default)
			)
			(fill no)
			(layer "F.CrtYd")
		)
		(fp_rect
			(start -0.2794 0.6477)
			(end 0.2794 -0.6477)
			(stroke
				(width 0)
				(type default)
			)
			(fill no)
			(layer "F.Fab")
		)
		(pad "1" smd custom
			(at 0 -0.2794 270)
			(size 0.0762 0.0762)
			(layers "F.Cu" "F.Mask" "F.Paste")
			(net "SAS_HDD_RX_P11")
			(options
				(clearance outline)
				(anchor circle)
			)
			(primitives
				(gr_poly
					(pts
						(arc
							(start 0.1524 -0.127)
							(mid 0.137521 -0.162921)
							(end 0.1016 -0.1778)
						)
						(arc
							(start -0.1016 -0.1778)
							(mid -0.137521 -0.162921)
							(end -0.1524 -0.127)
						)
						(arc
							(start -0.1524 0.127)
							(mid -0.137521 0.162921)
							(end -0.1016 0.1778)
						)
						(arc
							(start 0.1016 0.1778)
							(mid 0.137521 0.162921)
							(end 0.1524 0.127)
						)
					)
					(width 0)
					(fill yes)
				)
			)
		)
		(pad "2" smd custom
			(at 0 0.2794 270)
			(size 0.0762 0.0762)
			(layers "F.Cu" "F.Mask" "F.Paste")
			(net "PHY_SCC_A_TO_DRV_A_11_DP")
			(options
				(clearance outline)
				(anchor circle)
			)
			(primitives
				(gr_poly
					(pts
						(arc
							(start 0.1524 -0.127)
							(mid 0.137521 -0.162921)
							(end 0.1016 -0.1778)
						)
						(arc
							(start -0.1016 -0.1778)
							(mid -0.137521 -0.162921)
							(end -0.1524 -0.127)
						)
						(arc
							(start -0.1524 0.127)
							(mid -0.137521 0.162921)
							(end -0.1016 0.1778)
						)
						(arc
							(start 0.1016 0.1778)
							(mid 0.137521 0.162921)
							(end 0.1524 0.127)
						)
					)
					(width 0)
					(fill yes)
				)
			)
		)
	)
)
